# S9S_MB_2U (Grand Teton) — schematic netlist excerpt (pin names and nets, part order shuffled) for the footprints in the layout excerpt that follows; sources: Cadence DE-HDL packaged netlist, KiCad conversion of 03242023_DA0F0TMBIJ0_F0T_Motherboard_J_brd_V01_OCP.brd

C1936  Q_CAP  10UF 6.3V 20% X6S  pkg C0402  page 217 : A = VCC_PLD_CORE ; B = GND
R960  Q_RES  33.2 1% CHIP  pkg 0402LF  page 235 : A = SMB_PEHPCPU0_GTL_SCL ; B = SMB_PEHPCPU0_GTL_R_SCL

(kicad_pcb
	(version 20260206)
	(generator "pcbnew")
	(generator_version "10.0")
	(general
		(thickness 1.6)
		(legacy_teardrops no)
	)
	(paper "A4")
	(title_block
		(title "03242023_DA0F0TMBIJ0_F0T_Motherboard_J_brd_V01_OCP.brd")
		(comment 1 "Grand Teton / footprints 4366-4367 of 6105")
	)
	(layers
		(0 "F.Cu" signal "TOP")
		(4 "In1.Cu" signal "GND")
		(6 "In2.Cu" signal "IN1")
		(8 "In3.Cu" signal "GND1")
		(10 "In4.Cu" signal "IN2")
		(12 "In5.Cu" signal "GND2")
		(14 "In6.Cu" signal "IN3")
		(16 "In7.Cu" signal "GND3")
		(18 "In8.Cu" signal "VCC")
		(20 "In9.Cu" signal "VCC1")
		(22 "In10.Cu" signal "GND4")
		(24 "In11.Cu" signal "IN4")
		(26 "In12.Cu" signal "GND5")
		(28 "In13.Cu" signal "IN5")
		(30 "In14.Cu" signal "GND6")
		(32 "In15.Cu" signal "IN6")
		(34 "In16.Cu" signal "GND7")
		(2 "B.Cu" signal "BOTTOM")
		(9 "F.Adhes" user "F.Adhesive")
		(11 "B.Adhes" user "B.Adhesive")
		(13 "F.Paste" user "Package Geometry/Pastemask Top")
		(15 "B.Paste" user "Package Geometry/Pastemask Bottom")
		(5 "F.SilkS" user "Ref Des/Silkscreen Top")
		(7 "B.SilkS" user "Ref Des/Silkscreen Bottom")
		(1 "F.Mask" user "Board Geometry/Soldermask Top")
		(3 "B.Mask" user "Board Geometry/Soldermask Bottom")
		(17 "Dwgs.User" user "User.Drawings")
		(19 "Cmts.User" user "User.Comments")
		(21 "Eco1.User" user "User.Eco1")
		(23 "Eco2.User" user "User.Eco2")
		(25 "Edge.Cuts" user "Board Geometry/Outline")
		(27 "Margin" user)
		(31 "F.CrtYd" user "Package Geometry/Place Bound Top")
		(29 "B.CrtYd" user "Package Geometry/Place Bound Bottom")
		(35 "F.Fab" user "Ref Des/Assembly Top")
		(33 "B.Fab" user "Ref Des/Assembly Bottom")
	)
	(footprint ""
		(layer "B.Cu")
		(at 180.26888 -124.170948 180)
		(property "Reference" "C1936"
			(at 0 0 0)
			(layer "B.SilkS")
			(hide yes)
			(effects
				(font
					(size 1.27 1.27)
				)
				(justify mirror)
			)
		)
		(property "Value" ""
			(at 0 0 0)
			(layer "B.Fab")
			(effects
				(font
					(size 1.27 1.27)
				)
				(justify mirror)
			)
		)
		(duplicate_pad_numbers_are_jumpers no)
		(fp_line
			(start 0.7874 0.4064)
			(end 0.7874 -0.4064)
			(stroke
				(width 0.1524)
				(type default)
			)
			(layer "B.SilkS")
		)
		(fp_line
			(start 0.7874 -0.4064)
			(end -0.7874 -0.4064)
			(stroke
				(width 0.1524)
				(type default)
			)
			(layer "B.SilkS")
		)
		(fp_line
			(start -0.7874 0.4064)
			(end 0.7874 0.4064)
			(stroke
				(width 0.1524)
				(type default)
			)
			(layer "B.SilkS")
		)
		(fp_line
			(start -0.7874 -0.4064)
			(end -0.7874 0.4064)
			(stroke
				(width 0.1524)
				(type default)
			)
			(layer "B.SilkS")
		)
		(fp_line
			(start 0.67945 0.3048)
			(end 0.67945 -0.305054)
			(stroke
				(width 0.1)
				(type default)
			)
			(layer "B.Fab")
		)
		(fp_line
			(start 0.67945 -0.305054)
			(end 0.12065 -0.305054)
			(stroke
				(width 0.1)
				(type default)
			)
			(layer "B.Fab")
		)
		(fp_line
			(start 0.12065 0.3048)
			(end 0.67945 0.3048)
			(stroke
				(width 0.1)
				(type default)
			)
			(layer "B.Fab")
		)
		(fp_line
			(start 0.12065 0.2794)
			(end 0.12065 0.3048)
			(stroke
				(width 0.1)
				(type default)
			)
			(layer "B.Fab")
		)
		(fp_line
			(start 0.12065 -0.2794)
			(end -0.12065 -0.2794)
			(stroke
				(width 0.1)
				(type default)
			)
			(layer "B.Fab")
		)
		(fp_line
			(start 0.12065 -0.305054)
			(end 0.12065 -0.2794)
			(stroke
				(width 0.1)
				(type default)
			)
			(layer "B.Fab")
		)
		(fp_line
			(start -0.120396 0.3048)
			(end -0.120396 0.2794)
			(stroke
				(width 0.1)
				(type default)
			)
			(layer "B.Fab")
		)
		(fp_line
			(start -0.120396 0.2794)
			(end 0.12065 0.2794)
			(stroke
				(width 0.1)
				(type default)
			)
			(layer "B.Fab")
		)
		(fp_line
			(start -0.12065 -0.2794)
			(end -0.12065 -0.3048)
			(stroke
				(width 0.1)
				(type default)
			)
			(layer "B.Fab")
		)
		(fp_line
			(start -0.12065 -0.3048)
			(end -0.67945 -0.3048)
			(stroke
				(width 0.1)
				(type default)
			)
			(layer "B.Fab")
		)
		(fp_line
			(start -0.67945 0.3048)
			(end -0.120396 0.3048)
			(stroke
				(width 0.1)
				(type default)
			)
			(layer "B.Fab")
		)
		(fp_line
			(start -0.67945 -0.3048)
			(end -0.67945 0.3048)
			(stroke
				(width 0.1)
				(type default)
			)
			(layer "B.Fab")
		)
		(pad "1" smd circle
			(at 0.40005 0)
			(size 0 0)
			(layers "B.Cu" "B.Mask" "B.Paste")
			(net "VCC_PLD_CORE")
		)
		(pad "2" smd circle
			(at -0.40005 0)
			(size 0 0)
			(layers "B.Cu" "B.Mask" "B.Paste")
			(net "GND")
		)
	)
	(footprint ""
		(layer "B.Cu")
		(at 373.546624 -190.703454 90)
		(property "Reference" "R960"
			(at 0 0 90)
			(layer "B.SilkS")
			(hide yes)
			(effects
				(font
					(size 1.27 1.27)
				)
				(justify mirror)
			)
		)
		(property "Value" ""
			(at 0 0 90)
			(layer "B.Fab")
			(effects
				(font
					(size 1.27 1.27)
				)
				(justify mirror)
			)
		)
		(duplicate_pad_numbers_are_jumpers no)
		(fp_line
			(start 0.7874 -0.4064)
			(end -0.7874 -0.4064)
			(stroke
				(width 0.1524)
				(type default)
			)
			(layer "B.SilkS")
		)
		(fp_line
			(start -0.7874 -0.4064)
			(end -0.7874 0.4064)
			(stroke
				(width 0.1524)
				(type default)
			)
			(layer "B.SilkS")
		)
		(fp_line
			(start 0.7874 0.4064)
			(end 0.7874 -0.4064)
			(stroke
				(width 0.1524)
				(type default)
			)
			(layer "B.SilkS")
		)
		(fp_line
			(start -0.7874 0.4064)
			(end 0.7874 0.4064)
			(stroke
				(width 0.1524)
				(type default)
			)
			(layer "B.SilkS")
		)
		(fp_line
			(start 0.67945 -0.305054)
			(end 0.12065 -0.305054)
			(stroke
				(width 0.1)
				(type default)
			)
			(layer "B.Fab")
		)
		(fp_line
			(start 0.12065 -0.305054)
			(end 0.12065 -0.2794)
			(stroke
				(width 0.1)
				(type default)
			)
			(layer "B.Fab")
		)
		(fp_line
			(start -0.12065 -0.3048)
			(end -0.67945 -0.3048)
			(stroke
				(width 0.1)
				(type default)
			)
			(layer "B.Fab")
		)
		(fp_line
			(start -0.67945 -0.3048)
			(end -0.67945 0.3048)
			(stroke
				(width 0.1)
				(type default)
			)
			(layer "B.Fab")
		)
		(fp_line
			(start 0.12065 -0.2794)
			(end -0.12065 -0.2794)
			(stroke
				(width 0.1)
				(type default)
			)
			(layer "B.Fab")
		)
		(fp_line
			(start -0.12065 -0.2794)
			(end -0.12065 -0.3048)
			(stroke
				(width 0.1)
				(type default)
			)
			(layer "B.Fab")
		)
		(fp_line
			(start 0.12065 0.2794)
			(end 0.12065 0.3048)
			(stroke
				(width 0.1)
				(type default)
			)
			(layer "B.Fab")
		)
		(fp_line
			(start -0.120396 0.2794)
			(end 0.12065 0.2794)
			(stroke
				(width 0.1)
				(type default)
			)
			(layer "B.Fab")
		)
		(fp_line
			(start 0.67945 0.3048)
			(end 0.67945 -0.305054)
			(stroke
				(width 0.1)
				(type default)
			)
			(layer "B.Fab")
		)
		(fp_line
			(start 0.12065 0.3048)
			(end 0.67945 0.3048)
			(stroke
				(width 0.1)
				(type default)
			)
			(layer "B.Fab")
		)
		(fp_line
			(start -0.120396 0.3048)
			(end -0.120396 0.2794)
			(stroke
				(width 0.1)
				(type default)
			)
			(layer "B.Fab")
		)
		(fp_line
			(start -0.67945 0.3048)
			(end -0.120396 0.3048)
			(stroke
				(width 0.1)
				(type default)
			)
			(layer "B.Fab")
		)
		(pad "1" smd circle
			(at 0.40005 0 270)
			(size 0 0)
			(layers "B.Cu" "B.Mask" "B.Paste")
			(net "SMB_PEHPCPU0_GTL_SCL")
		)
		(pad "2" smd circle
			(at -0.40005 0 270)
			(size 0 0)
			(layers "B.Cu" "B.Mask" "B.Paste")
			(net "SMB_PEHPCPU0_GTL_R_SCL")
		)
	)
)
